# S9S_MB_2U (Grand Teton) — schematic netlist excerpt (pin names and nets, part order shuffled) for the footprints in the layout excerpt that follows; sources: Cadence DE-HDL packaged netlist, KiCad conversion of 03242023_DA0F0TMBIJ0_F0T_Motherboard_J_brd_V01_OCP.brd

J24  SCONN288_ADR50017P087CC  SCONN288_ADR50017-P087CC IO  pkg DDR288S_1-1VXB  page 105
  VIN_BULK0  = P12V_S3_AUX_CPU1_NVDIMM
  RFU0  = TP_CHD_CPU1_DIMM2_FRU_0
  VIN_MGMT  = P3V3_AUX
  HSCL  = I3C_SPD_DDRABCD_CPU1_LVC1_SCL_7
  HSDA  = I3C_SPD_DDRABCD_CPU1_LVC1_SDA
  VSS0  = GND
  DQ0_A  = M_D_CPU1_SA_DQ<0>
  VSS1  = GND
  DQ1_A  = M_D_CPU1_SA_DQ<1>
  VSS2  = GND
  DQS0_A_T  = M_D_CPU1_SA_DQS_DP<0>
  DQS0_A_C  = M_D_CPU1_SA_DQS_DN<0>
  VSS3  = GND
  DQ4_A  = M_D_CPU1_SA_DQ<4>
  VSS4  = GND
  DQ5_A  = M_D_CPU1_SA_DQ<5>
  VSS5  = GND
  DQ8_A  = M_D_CPU1_SA_DQ<8>
  VSS6  = GND
  DQ9_A  = M_D_CPU1_SA_DQ<9>
  VSS7  = GND
  DQS1_A_T  = M_D_CPU1_SA_DQS_DP<1>
  DQS1_A_C  = M_D_CPU1_SA_DQS_DN<1>
  VSS8  = GND
  DQ12_A  = M_D_CPU1_SA_DQ<12>
  VSS9  = GND
  DQ13_A  = M_D_CPU1_SA_DQ<13>
  VSS10  = GND
  DQ16_A  = M_D_CPU1_SA_DQ<16>
  VSS11  = GND
  DQ17_A  = M_D_CPU1_SA_DQ<17>
  VSS12  = GND
  DQS2_A_T  = M_D_CPU1_SA_DQS_DP<2>
  DQS2_A_C  = M_D_CPU1_SA_DQS_DN<2>
  VSS13  = GND
  DQ20_A  = M_D_CPU1_SA_DQ<20>
  VSS14  = GND
  DQ21_A  = M_D_CPU1_SA_DQ<21>
  VSS15  = GND
  DQ24_A  = M_D_CPU1_SA_DQ<24>
  VSS16  = GND
  DQ25_A  = M_D_CPU1_SA_DQ<25>
  VSS17  = GND
  DQS3_A_T  = M_D_CPU1_SA_DQS_DP<3>
  DQS3_A_C  = M_D_CPU1_SA_DQS_DN<3>
  VSS18  = GND
  DQ28_A  = M_D_CPU1_SA_DQ<28>
  VSS19  = GND
  DQ29_A  = M_D_CPU1_SA_DQ<29>
  VSS20  = GND
  CB0_A  = M_D_CPU1_SA_CB<0>
  VSS21  = GND
  CB1_A  = M_D_CPU1_SA_CB<1>
  VSS22  = GND
  DQS4_A_T  = M_D_CPU1_SA_DQS_DP<4>
  DQS4_A_C  = M_D_CPU1_SA_DQS_DN<4>
  VSS23  = GND
  CB4_A  = M_D_CPU1_SA_CB<4>
  VSS24  = GND
  CB5_A  = M_D_CPU1_SA_CB<5>
  VSS25  = GND
  ALERT_N  = M_D_CPU1_ALERT_N
  VSS26  = GND
  CS0_A_N  = M_D_CPU1_SA_CS_N<2>
  VSS27  = GND
  CA0_A  = M_D_CPU1_SA_CA<0>
  VSS28  = GND
  CA2_A  = M_D_CPU1_SA_CA<2>
  VSS29  = GND
  CA4_A  = M_D_CPU1_SA_CA<4>
  VSS30  = GND
  CA6_A  = M_D_CPU1_SA_CA<6>
  VSS31  = GND
  PAR_A  = M_D_CPU1_SA_PAR
  VSS32  = GND
  CA0_B  = M_D_CPU1_SB_CA<0>
  VSS33  = GND
  CA2_B  = M_D_CPU1_SB_CA<2>
  VSS34  = GND
  CA4_B  = M_D_CPU1_SB_CA<4>
  VSS35  = GND
  CA6_B  = M_D_CPU1_SB_CA<6>
  VSS36  = GND
  CS0_B_N  = M_D_CPU1_SB_CS_N<2>
  VSS37  = GND
  \lbd||rsp_a_n\  = M_D_CPU1_SA_RSP<1>
  \lbs||rsp_b_n\  = M_D_CPU1_SB_RSP<1>
  VSS38  = GND
  CB4_B  = M_D_CPU1_SB_CB<4>
  VSS39  = GND
  CB5_B  = M_D_CPU1_SB_CB<5>
  VSS40  = GND
  \dqs9_b_t||tdqs9_b_t||dbi4_b_n\  = M_D_CPU1_SB_DQS_DP<9>
  \dqs9_b_c||tdqs9_b_c\  = M_D_CPU1_SB_DQS_DN<9>
  VSS41  = GND
  CB0_B  = M_D_CPU1_SB_CB<0>
  VSS42  = GND
  CB1_B  = M_D_CPU1_SB_CB<1>
  VSS43  = GND
  DQ0_B  = M_D_CPU1_SB_DQ<0>
  VSS44  = GND
  DQ1_B  = M_D_CPU1_SB_DQ<1>
  VSS45  = GND
  DQS0_B_T  = M_D_CPU1_SB_DQS_DP<0>
  DQS0_B_C  = M_D_CPU1_SB_DQS_DN<0>
  VSS46  = GND
  DQ4_B  = M_D_CPU1_SB_DQ<4>
  VSS47  = GND
  DQ5_B  = M_D_CPU1_SB_DQ<5>
  VSS48  = GND
  DQ8_B  = M_D_CPU1_SB_DQ<8>
  VSS49  = GND
  DQ9_B  = M_D_CPU1_SB_DQ<9>
  VSS50  = GND
  DQS1_B_T  = M_D_CPU1_SB_DQS_DP<1>
  DQS1_B_C  = M_D_CPU1_SB_DQS_DN<1>
  VSS51  = GND
  DQ12_B  = M_D_CPU1_SB_DQ<12>
  VSS52  = GND
  DQ13_B  = M_D_CPU1_SB_DQ<13>
  VSS53  = GND
  DQ16_B  = M_D_CPU1_SB_DQ<16>
  VSS54  = GND
  DQ17_B  = M_D_CPU1_SB_DQ<17>
  VSS55  = GND
  DQS2_B_T  = M_D_CPU1_SB_DQS_DP<2>
  DQS2_B_C  = M_D_CPU1_SB_DQS_DN<2>
  VSS56  = GND
  DQ20_B  = M_D_CPU1_SB_DQ<20>
  VSS57  = GND
  DQ21_B  = M_D_CPU1_SB_DQ<21>
  VSS58  = GND
  DQ24_B  = M_D_CPU1_SB_DQ<24>
  VSS59  = GND
  DQ25_B  = M_D_CPU1_SB_DQ<25>
  VSS60  = GND
  DQS3_B_T  = M_D_CPU1_SB_DQS_DP<3>
  DQS3_B_C  = M_D_CPU1_SB_DQS_DN<3>
  VSS61  = GND
  DQ28_B  = M_D_CPU1_SB_DQ<28>
  VSS62  = GND
  DQ29_B  = M_D_CPU1_SB_DQ<29>
  VSS63  = GND
  RFU1  = TP_CHD_CPU1_DIMM2_FRU_1
  VIN_BULK1  = P12V_S3_AUX_CPU1_NVDIMM
  VIN_BULK2  = P12V_S3_AUX_CPU1_NVDIMM
  \pwr_good||fail_n\  = PWRGD_CHD_CPU1_DIMM2
  HSA  = PD_CHD_CPU1_DIMM2_SAA
  RFU2  = TP_CHD_CPU1_DIMM2_FRU_2
  RFU3  = TP_CHD_CPU1_DIMM2_FRU_3
  VSS64  = GND
  DQ2_A  = M_D_CPU1_SA_DQ<2>
  VSS65  = GND
  DQ3_A  = M_D_CPU1_SA_DQ<3>
  VSS66  = GND
  \dqs5_a_c||tdqs5_a_c||dqs5_a_t||tdqs5_a_t\  = M_D_CPU1_SA_DQS_DN<5>
  \dqs5_a_t||tdqs5_a_t\  = M_D_CPU1_SA_DQS_DP<5>
  VSS67  = GND
  DQ6_A  = M_D_CPU1_SA_DQ<6>
  VSS68  = GND
  DQ7_A  = M_D_CPU1_SA_DQ<7>
  VSS69  = GND
  DQ10_A  = M_D_CPU1_SA_DQ<10>
  VSS70  = GND
  DQ11_A  = M_D_CPU1_SA_DQ<11>
  VSS71  = GND
  \dqs6_a_c||tdqs6_a_c||dqs6_a_t||tdqs6_a_t\  = M_D_CPU1_SA_DQS_DN<6>
  \dqs6_a_t||tdqs6_a_t\  = M_D_CPU1_SA_DQS_DP<6>
  VSS72  = GND
  DQ14_A  = M_D_CPU1_SA_DQ<14>
  VSS73  = GND
  DQ15_A  = M_D_CPU1_SA_DQ<15>
  VSS74  = GND
  DQ18_A  = M_D_CPU1_SA_DQ<18>
  VSS75  = GND
  DQ19_A  = M_D_CPU1_SA_DQ<19>
  VSS76  = GND
  \dqs7_a_c||tdqs7_a_c\  = M_D_CPU1_SA_DQS_DN<7>
  \dqs7_a_t||tdqs7_a_t\  = M_D_CPU1_SA_DQS_DP<7>
  VSS77  = GND
  DQ22_A  = M_D_CPU1_SA_DQ<22>
  VSS78  = GND
  DQ23_A  = M_D_CPU1_SA_DQ<23>
  VSS79  = GND
  DQ26_A  = M_D_CPU1_SA_DQ<26>
  VSS80  = GND
  DQ27_A  = M_D_CPU1_SA_DQ<27>
  VSS81  = GND
  \dqs8_a_c||tdqs8_a_c\  = M_D_CPU1_SA_DQS_DN<8>
  \dqs8_a_t||tdqs8_a_t\  = M_D_CPU1_SA_DQS_DP<8>
  VSS82  = GND
  DQ30_A  = M_D_CPU1_SA_DQ<30>
  VSS83  = GND
  DQ31_A  = M_D_CPU1_SA_DQ<31>
  VSS84  = GND
  CB2_A  = M_D_CPU1_SA_CB<2>
  VSS85  = GND
  CB3_A  = M_D_CPU1_SA_CB<3>
  VSS86  = GND
  \dqs9_a_c||tdqs9_a_c\  = M_D_CPU1_SA_DQS_DN<9>
  \dqs9_a_t||tdqs9_a_t\  = M_D_CPU1_SA_DQS_DP<9>
  VSS87  = GND
  CB6_A  = M_D_CPU1_SA_CB<6>
  VSS88  = GND
  CB7_A  = M_D_CPU1_SA_CB<7>
  VSS89  = GND
  RESET_N  = RST_M_CD_CPU1_FPGA_N
  VSS90  = GND
  CS1_A_N  = M_D_CPU1_SA_CS_N<3>
  VSS91  = GND
  CA1_A  = M_D_CPU1_SA_CA<1>
  VSS92  = GND
  CA3_A  = M_D_CPU1_SA_CA<3>
  VSS93  = GND
  CA5_A  = M_D_CPU1_SA_CA<5>
  VSS94  = GND
  CK_T  = M_D_CPU1_CLK_DP<1>
  CK_C  = M_D_CPU1_CLK_DN<1>
  VSS95  = GND
  RFU4  = TP_CHD_CPU1_DIMM2_FRU_4
  CA1_B  = M_D_CPU1_SB_CA<1>
  VSS96  = GND
  CA3_B  = M_D_CPU1_SB_CA<3>
  VSS97  = GND
  CA5_B  = M_D_CPU1_SB_CA<5>
  VSS98  = GND
  PAR_B  = M_D_CPU1_SB_PAR
  VSS99  = GND
  CS1_B_N  = M_D_CPU1_SB_CS_N<3>
  VSS100  = GND
  RFU5  = TP_CHD_CPU1_DIMM2_FRU_5
  RFU6  = TP_CHD_CPU1_DIMM2_FRU_6
  VSS101  = GND
  CB6_B  = M_D_CPU1_SB_CB<6>
  VSS102  = GND
  CB7_B  = M_D_CPU1_SB_CB<7>
  VSS103  = GND
  DQS4_B_C  = M_D_CPU1_SB_DQS_DN<4>
  DQS4_B_T  = M_D_CPU1_SB_DQS_DP<4>
  VSS104  = GND
  CB2_B  = M_D_CPU1_SB_CB<2>
  VSS105  = GND
  CB3_B  = M_D_CPU1_SB_CB<3>
  VSS106  = GND
  DQ2_B  = M_D_CPU1_SB_DQ<2>
  VSS107  = GND
  DQ3_B  = M_D_CPU1_SB_DQ<3>
  VSS108  = GND
  \dqs5_b_c||tdqs5_b_c\  = M_D_CPU1_SB_DQS_DN<5>
  \dqs5_b_t||tdqs5_b_t\  = M_D_CPU1_SB_DQS_DP<5>
  VSS109  = GND
  DQ6_B  = M_D_CPU1_SB_DQ<6>
  VSS110  = GND
  DQ7_B  = M_D_CPU1_SB_DQ<7>
  VSS111  = GND
  DQ10_B  = M_D_CPU1_SB_DQ<10>
  VSS112  = GND
  DQ11_B  = M_D_CPU1_SB_DQ<11>
  VSS113  = GND
  \dqs6_b_c||tdqs6_b_c\  = M_D_CPU1_SB_DQS_DN<6>
  \dqs6_b_t||tdqs6_b_t\  = M_D_CPU1_SB_DQS_DP<6>
  VSS114  = GND
  DQ14_B  = M_D_CPU1_SB_DQ<14>
  VSS115  = GND
  DQ15_B  = M_D_CPU1_SB_DQ<15>
  VSS116  = GND
  DQ18_B  = M_D_CPU1_SB_DQ<18>
  VSS117  = GND
  DQ19_B  = M_D_CPU1_SB_DQ<19>
  VSS118  = GND
  \dqs7_b_c||tdqs7_b_c\  = M_D_CPU1_SB_DQS_DN<7>
  \dqs7_b_t||tdqs7_b_t\  = M_D_CPU1_SB_DQS_DP<7>
  VSS119  = GND
  DQ22_B  = M_D_CPU1_SB_DQ<22>
  VSS120  = GND
  DQ23_B  = M_D_CPU1_SB_DQ<23>
  VSS121  = GND
  DQ26_B  = M_D_CPU1_SB_DQ<26>
  VSS122  = GND
  DQ27_B  = M_D_CPU1_SB_DQ<27>
  VSS123  = GND
  \dqs8_b_c||tdqs8_b_c\  = M_D_CPU1_SB_DQS_DN<8>
  \dqs8_b_t||tdqs8_b_t\  = M_D_CPU1_SB_DQS_DP<8>
  VSS124  = GND
  DQ30_B  = M_D_CPU1_SB_DQ<30>
  VSS125  = GND
  DQ31_B  = M_D_CPU1_SB_DQ<31>
  VSS126  = GND
  G1  = GND
  G2  = GND
  G3  = GND

(kicad_pcb
	(version 20260206)
	(generator "pcbnew")
	(generator_version "10.0")
	(general
		(thickness 1.6)
		(legacy_teardrops no)
	)
	(paper "A4")
	(title_block
		(title "03242023_DA0F0TMBIJ0_F0T_Motherboard_J_brd_V01_OCP.brd")
		(comment 1 "Grand Teton / footprint 1660 of 6105 (J24), pads 46-91 of 291")
	)
	(layers
		(0 "F.Cu" signal "TOP")
		(4 "In1.Cu" signal "GND")
		(6 "In2.Cu" signal "IN1")
		(8 "In3.Cu" signal "GND1")
		(10 "In4.Cu" signal "IN2")
		(12 "In5.Cu" signal "GND2")
		(14 "In6.Cu" signal "IN3")
		(16 "In7.Cu" signal "GND3")
		(18 "In8.Cu" signal "VCC")
		(20 "In9.Cu" signal "VCC1")
		(22 "In10.Cu" signal "GND4")
		(24 "In11.Cu" signal "IN4")
		(26 "In12.Cu" signal "GND5")
		(28 "In13.Cu" signal "IN5")
		(30 "In14.Cu" signal "GND6")
		(32 "In15.Cu" signal "IN6")
		(34 "In16.Cu" signal "GND7")
		(2 "B.Cu" signal "BOTTOM")
		(9 "F.Adhes" user "F.Adhesive")
		(11 "B.Adhes" user "B.Adhesive")
		(13 "F.Paste" user "Package Geometry/Pastemask Top")
		(15 "B.Paste" user "Package Geometry/Pastemask Bottom")
		(5 "F.SilkS" user "Ref Des/Silkscreen Top")
		(7 "B.SilkS" user "Ref Des/Silkscreen Bottom")
		(1 "F.Mask" user "Board Geometry/Soldermask Top")
		(3 "B.Mask" user "Board Geometry/Soldermask Bottom")
		(17 "Dwgs.User" user "User.Drawings")
		(19 "Cmts.User" user "User.Comments")
		(21 "Eco1.User" user "User.Eco1")
		(23 "Eco2.User" user "User.Eco2")
		(25 "Edge.Cuts" user "Board Geometry/Outline")
		(27 "Margin" user)
		(31 "F.CrtYd" user "Package Geometry/Place Bound Top")
		(29 "B.CrtYd" user "Package Geometry/Place Bound Bottom")
		(35 "F.Fab" user "Ref Des/Assembly Top")
		(33 "B.Fab" user "Ref Des/Assembly Bottom")
	)
	(footprint ""
		(layer "F.Cu")
		(at 17.73428 -258.091686)
		(property "Reference" "J24"
			(at -3.0607 -81.901792 0)
			(unlocked yes)
			(layer "F.SilkS")
			(effects
				(font
					(size 0.7874 0.5842)
					(thickness 0.1524)
				)
				(justify left)
			)
		)
		(property "Value" ""
			(at 0 0 0)
			(layer "F.Fab")
			(effects
				(font
					(size 1.27 1.27)
				)
			)
		)
		(duplicate_pad_numbers_are_jumpers no)
		(pad "46" smd rect
			(at -2.050034 -25.07488 270)
			(size 0.519938 1.4986)
			(layers "F.Cu" "F.Mask" "F.Paste")
			(net "GND")
		)
		(pad "47" smd rect
			(at -2.050034 -24.224996 270)
			(size 0.519938 1.4986)
			(layers "F.Cu" "F.Mask" "F.Paste")
			(net "M_D_CPU1_SA_DQ<28>")
		)
		(pad "48" smd rect
			(at -2.050034 -23.375112 270)
			(size 0.519938 1.4986)
			(layers "F.Cu" "F.Mask" "F.Paste")
			(net "GND")
		)
		(pad "49" smd rect
			(at -2.050034 -22.524974 270)
			(size 0.519938 1.4986)
			(layers "F.Cu" "F.Mask" "F.Paste")
			(net "M_D_CPU1_SA_DQ<29>")
		)
		(pad "50" smd rect
			(at -2.050034 -21.67509 270)
			(size 0.519938 1.4986)
			(layers "F.Cu" "F.Mask" "F.Paste")
			(net "GND")
		)
		(pad "51" smd rect
			(at -2.050034 -20.824952 270)
			(size 0.519938 1.4986)
			(layers "F.Cu" "F.Mask" "F.Paste")
			(net "M_D_CPU1_SA_CB<0>")
		)
		(pad "52" smd rect
			(at -2.050034 -19.975068 270)
			(size 0.519938 1.4986)
			(layers "F.Cu" "F.Mask" "F.Paste")
			(net "GND")
		)
		(pad "53" smd rect
			(at -2.050034 -19.12493 270)
			(size 0.519938 1.4986)
			(layers "F.Cu" "F.Mask" "F.Paste")
			(net "M_D_CPU1_SA_CB<1>")
		)
		(pad "54" smd rect
			(at -2.050034 -18.275046 270)
			(size 0.519938 1.4986)
			(layers "F.Cu" "F.Mask" "F.Paste")
			(net "GND")
		)
		(pad "55" smd rect
			(at -2.050034 -17.424908 270)
			(size 0.519938 1.4986)
			(layers "F.Cu" "F.Mask" "F.Paste")
			(net "M_D_CPU1_SA_DQS_DP<4>")
		)
		(pad "56" smd rect
			(at -2.050034 -16.575024 270)
			(size 0.519938 1.4986)
			(layers "F.Cu" "F.Mask" "F.Paste")
			(net "M_D_CPU1_SA_DQS_DN<4>")
		)
		(pad "57" smd rect
			(at -2.050034 -15.724886 270)
			(size 0.519938 1.4986)
			(layers "F.Cu" "F.Mask" "F.Paste")
			(net "GND")
		)
		(pad "58" smd rect
			(at -2.050034 -14.875002 270)
			(size 0.519938 1.4986)
			(layers "F.Cu" "F.Mask" "F.Paste")
			(net "M_D_CPU1_SA_CB<4>")
		)
		(pad "59" smd rect
			(at -2.050034 -14.025118 270)
			(size 0.519938 1.4986)
			(layers "F.Cu" "F.Mask" "F.Paste")
			(net "GND")
		)
		(pad "60" smd rect
			(at -2.050034 -13.17498 270)
			(size 0.519938 1.4986)
			(layers "F.Cu" "F.Mask" "F.Paste")
			(net "M_D_CPU1_SA_CB<5>")
		)
		(pad "61" smd rect
			(at -2.050034 -12.325096 270)
			(size 0.519938 1.4986)
			(layers "F.Cu" "F.Mask" "F.Paste")
			(net "GND")
		)
		(pad "62" smd rect
			(at -2.050034 -11.474958 270)
			(size 0.519938 1.4986)
			(layers "F.Cu" "F.Mask" "F.Paste")
			(net "M_D_CPU1_ALERT_N")
		)
		(pad "63" smd rect
			(at -2.050034 -10.625074 270)
			(size 0.519938 1.4986)
			(layers "F.Cu" "F.Mask" "F.Paste")
			(net "GND")
		)
		(pad "64" smd rect
			(at -2.050034 -9.774936 270)
			(size 0.519938 1.4986)
			(layers "F.Cu" "F.Mask" "F.Paste")
			(net "M_D_CPU1_SA_CS_N<2>")
		)
		(pad "65" smd rect
			(at -2.050034 -8.925052 270)
			(size 0.519938 1.4986)
			(layers "F.Cu" "F.Mask" "F.Paste")
			(net "GND")
		)
		(pad "66" smd rect
			(at -2.050034 -8.074914 270)
			(size 0.519938 1.4986)
			(layers "F.Cu" "F.Mask" "F.Paste")
			(net "M_D_CPU1_SA_CA<0>")
		)
		(pad "67" smd rect
			(at -2.050034 -7.22503 270)
			(size 0.519938 1.4986)
			(layers "F.Cu" "F.Mask" "F.Paste")
			(net "GND")
		)
		(pad "68" smd rect
			(at -2.050034 -6.374892 270)
			(size 0.519938 1.4986)
			(layers "F.Cu" "F.Mask" "F.Paste")
			(net "M_D_CPU1_SA_CA<2>")
		)
		(pad "69" smd rect
			(at -2.050034 -5.525008 270)
			(size 0.519938 1.4986)
			(layers "F.Cu" "F.Mask" "F.Paste")
			(net "GND")
		)
		(pad "70" smd rect
			(at -2.050034 -4.675124 270)
			(size 0.519938 1.4986)
			(layers "F.Cu" "F.Mask" "F.Paste")
			(net "M_D_CPU1_SA_CA<4>")
		)
		(pad "71" smd rect
			(at -2.050034 -3.824986 270)
			(size 0.519938 1.4986)
			(layers "F.Cu" "F.Mask" "F.Paste")
			(net "GND")
		)
		(pad "72" smd rect
			(at -2.050034 -2.975102 270)
			(size 0.519938 1.4986)
			(layers "F.Cu" "F.Mask" "F.Paste")
			(net "M_D_CPU1_SA_CA<6>")
		)
		(pad "73" smd rect
			(at -2.050034 -2.124964 270)
			(size 0.519938 1.4986)
			(layers "F.Cu" "F.Mask" "F.Paste")
			(net "GND")
		)
		(pad "74" smd rect
			(at -2.050034 -1.27508 270)
			(size 0.519938 1.4986)
			(layers "F.Cu" "F.Mask" "F.Paste")
			(net "M_D_CPU1_SA_PAR")
		)
		(pad "75" smd rect
			(at -2.050034 -0.424942 270)
			(size 0.519938 1.4986)
			(layers "F.Cu" "F.Mask" "F.Paste")
			(net "GND")
		)
		(pad "76" smd rect
			(at -2.050034 5.525008 270)
			(size 0.519938 1.4986)
			(layers "F.Cu" "F.Mask" "F.Paste")
			(net "M_D_CPU1_SB_CA<0>")
		)
		(pad "77" smd rect
			(at -2.050034 6.374892 270)
			(size 0.519938 1.4986)
			(layers "F.Cu" "F.Mask" "F.Paste")
			(net "GND")
		)
		(pad "78" smd rect
			(at -2.050034 7.22503 270)
			(size 0.519938 1.4986)
			(layers "F.Cu" "F.Mask" "F.Paste")
			(net "M_D_CPU1_SB_CA<2>")
		)
		(pad "79" smd rect
			(at -2.050034 8.074914 270)
			(size 0.519938 1.4986)
			(layers "F.Cu" "F.Mask" "F.Paste")
			(net "GND")
		)
		(pad "80" smd rect
			(at -2.050034 8.925052 270)
			(size 0.519938 1.4986)
			(layers "F.Cu" "F.Mask" "F.Paste")
			(net "M_D_CPU1_SB_CA<4>")
		)
		(pad "81" smd rect
			(at -2.050034 9.774936 270)
			(size 0.519938 1.4986)
			(layers "F.Cu" "F.Mask" "F.Paste")
			(net "GND")
		)
		(pad "82" smd rect
			(at -2.050034 10.625074 270)
			(size 0.519938 1.4986)
			(layers "F.Cu" "F.Mask" "F.Paste")
			(net "M_D_CPU1_SB_CA<6>")
		)
		(pad "83" smd rect
			(at -2.050034 11.474958 270)
			(size 0.519938 1.4986)
			(layers "F.Cu" "F.Mask" "F.Paste")
			(net "GND")
		)
		(pad "84" smd rect
			(at -2.050034 12.325096 270)
			(size 0.519938 1.4986)
			(layers "F.Cu" "F.Mask" "F.Paste")
			(net "M_D_CPU1_SB_CS_N<2>")
		)
		(pad "85" smd rect
			(at -2.050034 13.17498 270)
			(size 0.519938 1.4986)
			(layers "F.Cu" "F.Mask" "F.Paste")
			(net "GND")
		)
		(pad "86" smd rect
			(at -2.050034 14.025118 270)
			(size 0.519938 1.4986)
			(layers "F.Cu" "F.Mask" "F.Paste")
			(net "M_D_CPU1_SA_RSP<1>")
		)
		(pad "87" smd rect
			(at -2.050034 14.875002 270)
			(size 0.519938 1.4986)
			(layers "F.Cu" "F.Mask" "F.Paste")
			(net "M_D_CPU1_SB_RSP<1>")
		)
		(pad "88" smd rect
			(at -2.050034 15.724886 270)
			(size 0.519938 1.4986)
			(layers "F.Cu" "F.Mask" "F.Paste")
			(net "GND")
		)
		(pad "89" smd rect
			(at -2.050034 16.575024 270)
			(size 0.519938 1.4986)
			(layers "F.Cu" "F.Mask" "F.Paste")
			(net "M_D_CPU1_SB_CB<4>")
		)
		(pad "90" smd rect
			(at -2.050034 17.424908 270)
			(size 0.519938 1.4986)
			(layers "F.Cu" "F.Mask" "F.Paste")
			(net "GND")
		)
		(pad "91" smd rect
			(at -2.050034 18.275046 270)
			(size 0.519938 1.4986)
			(layers "F.Cu" "F.Mask" "F.Paste")
			(net "M_D_CPU1_SB_CB<5>")
		)
	)
)
